FILE_TYPE = CONNECTIVITY;
{Allegro Design Entry HDL 16.6-p007 (v16-6-112F) 10/10/2012}
"PAGE_NUMBER" = 185;
0"NC";
1"P3V3\g";
2"P3V3_STBY\g";
3"P3V3_STBY\g";
4"GND\g";
5"GND\g";
6"P3V3\g";
7"P3V3\g";
8"GND\g";
9"P3V3\g";
10"GND\g";
11"P3V3\g";
12"GND\g";
13"P3V3\g";
14"SATA6G_S0_TX_DP";
15"P3E_PCH_M2_SATA6G_TX_R_DP";
16"P3E_PCH_M2_TX_DN<2>";
17"P3E_PCH_M2_TX_C_DP<2>";
18"P3E_PCH_M2_TX_C_DN<3>";
19"P3E_PCH_M2_TX_DN<3>";
20"P3E_PCH_M2_TX_DP<3>";
21"P3E_PCH_M2_SATA6G_RX_R_DN";
22"P3E_PCH_M2_SATA6G_RX_R_DP";
23"P3E_PCH_M2_SATA6G_TX_R_DN";
24"P3E_PCH_M2_TX_DP<1>";
25"P3E_PCH_M2_TX_DN<1>";
26"P3E_PCH_M2_TX_DP<2>";
27"PU_M2_CLK_REQ_N";
28"P3E_PCH_RX_0_DN";
29"SATA6G_S0_RX_DN";
30"P3E_PCH_RX_0_DP";
31"SATA6G_S0_RX_DP";
32"P3E_PCH_TX_0_DN";
33"SATA6G_S0_TX_DN";
34"P3E_PCH_TX_0_DP";
35"P3E_PCH_M2_TX_C_DN<2>";
36"P3E_PCH_M2_TX_C_DP<3>";
37"P3E_PCH_M2_TX_C_DN<1>";
38"P3E_PCH_M2_TX_C_DP<1>";
39"P3E_PCH_M2_RX_DN<1>";
40"P3E_PCH_M2_RX_DP<1>";
41"P3E_PCH_M2_RX_DN<2>";
42"P3E_PCH_M2_RX_DP<2>";
43"P3E_PCH_M2_RX_DN<3>";
44"P3E_PCH_M2_RX_DP<3>";
45"TP_M2_DEVSLP";
46"TP_M2_32M_SUSCLK";
47"FM_PE_M2_WAKE_N";
48"RST_PCIE_M2_DEV_N";
49"CLK_100M_M2_DP";
50"CLK_100M_M2_DN";
51"FM_SSATA_PCIE_M2_SEL";
52"FM_M2_DET_LVC3";
53"NC_M2<0>";
54"NC_M2<7>";
55"NC_M2<6>";
56"NC_M2<8>";
57"NC_M2<5>";
58"NC_M2<1>";
59"NC_M2<2>";
60"NC_M2<3>";
61"NC_M2<4>";
62"NC_M2<18>";
63"NC_M2<9>";
64"NC_M2<10>";
65"NC_M2<11>";
66"NC_M2<12>";
67"NC_M2<13>";
68"NC_M2<14>";
69"NC_M2<15>";
70"NC_M2<16>";
71"NC_M2<17>";
72"FM_M2_SSD_PEDET";
73"TP_LED_M2_ACT_N";
74"P3E_PCH_M2_SATA6G_RX_R_DP";
75"P3E_PCH_M2_SATA6G_RX_R_DN";
76"P3E_PCH_M2_SATA6G_TX_R_DP";
77"P3E_PCH_M2_SATA6G_TX_R_DN";
%"RES"
"1","(-2900,1050)","0","mstr_discrete","I105";
;
CDS_SEC"1"
BOM_COST"ST_FLASH"
ROOM"M_2"
SEC_TYPE"0402"
CDS_LIB"mstr_discrete"
SEC"1"
CDS_LOCATION"R8F18"
PART_NUMBER"G21497-005"
PACK_TYPE"0402"
WATTAGE"1/16W"
MATERIAL"CHIP"
TOLERANCE"5%"
VALUE"0.0"
LOCATION"R8F18";
"B"
$PN"2"22;
"A"
$PN"1"30;
%"RES"
"1","(-2875,600)","0","mstr_discrete","I106";
;
CDS_SEC"1"
ROOM"M_2"
BOM_COST"ST_FLASH"
SEC"1"
SEC_TYPE"0402"
CDS_LIB"mstr_discrete"
CDS_LOCATION"R8F21"
PACK_TYPE"0402"
PART_NUMBER"G21497-005"
WATTAGE"1/16W"
MATERIAL"CHIP"
TOLERANCE"5%"
LOCATION"R8F21"
VALUE"0.0";
"B"
$PN"2"21;
"A"
$PN"1"28;
%"TTL1G07_A"
"1","(-6375,1250)","0","mstr_ttl","I110";
;
CDS_SEC"1"
CDS_LOCATION"U2P1"
ROOM"M_2"
BOM_COST"ST_FLASH"
SEC_TYPE"SOP"
PACK_TYPE"SOP"
CDS_LIB"mstr_ttl"
SEC"1"
VALUE"74LVC1G07"
PART_NUMBER"C88419-001"
POWER_GROUP"VCC=P3V3_STBY;GND=GND"
MATERIAL"IC"
LOCATION"U2P1";
"Y"
$PN"4"52;
"A"
$PN"2"72;
%"RES"
"2","(-6725,1525)","0","mstr_discrete","I111";
;
CDS_SEC"1"
CDS_LOCATION"R2P15"
BOM_COST"ST_FLASH"
SEC_TYPE"0402"
ROOM"M_2"
SEC"1"
CDS_LIB"mstr_discrete"
WATTAGE"1/16W"
LOCATION"R2P15"
PART_NUMBER"G21796-016"
VALUE"10.0K"
TOLERANCE"1%"
PACK_TYPE"0402"
MATERIAL"CHIP";
"A"
$PN"1"1;
"B"
$PN"2"72;
%"P3V3"
"1","(-6725,1725)","0","mstr_symbols","I112";
;
VOLTAGE"3.3V"
SIZE"1B"
CDS_LIB"mstr_symbols"
BODY_TYPE"PLUMBING"
HDL_POWER"P3V3";
"G\NAC"1;
%"RES"
"2","(-6025,1525)","0","mstr_discrete","I113";
;
CDS_SEC"1"
CDS_LOCATION"R2P16"
BOM_COST"ST_FLASH"
SEC_TYPE"0402"
ROOM"M_2"
SEC"1"
CDS_LIB"mstr_discrete"
PACK_TYPE"0402"
LOCATION"R2P16"
VALUE"10.0K"
TOLERANCE"1%"
PART_NUMBER"G21796-016"
MATERIAL"CHIP"
WATTAGE"1/16W";
"A"
$PN"1"2;
"B"
$PN"2"52;
%"P3V3_STBY"
"1","(-6025,1725)","0","mstr_symbols","I114";
;
SIZE"1B"
BODY_TYPE"PLUMBING"
CDS_LIB"mstr_symbols"
VOLTAGE"3.3V"
HDL_POWER"P3V3_STBY";
"G\NAC"2;
%"RES"
"1","(-5650,1250)","0","mstr_discrete","I115";
;
CDS_SEC"1"
CDS_LOCATION"R2P14"
BOM_COST"ST_FLASH"
ROOM"M_2"
SEC_TYPE"0402"
SEC"1"
CDS_LIB"mstr_discrete"
PACK_TYPE"0402"
LOCATION"R2P14"
PART_NUMBER"G21497-005"
TOLERANCE"5%"
MATERIAL"CHIP"
WATTAGE"1/16W"
VALUE"0.0";
"B"
$PN"2"51;
"A"
$PN"1"52;
%"CAP_A"
"1","(-6425,700)","0","dev_discrete","I117";
;
CDS_LOCATION"C2P9"
BOM_COST"SD_FLASH"
ROOM"M_2"
CDS_SEC"1"
SEC"1"
SEC_TYPE"0402V"
CDS_LIB"dev_discrete"
VOLTAGE"16V"
PART_NUMBER"A36096-030"
LOCATION"C2P9"
VALUE"0.1UF"
TOLERANCE"10%"
MATERIAL"X7R"
PACK_TYPE"0402V";
"B"
$PN"2"4;
"A"
$PN"1"3;
%"P3V3_STBY"
"1","(-6425,925)","0","mstr_symbols","I118";
;
SIZE"1B"
BODY_TYPE"PLUMBING"
CDS_LIB"mstr_symbols"
VOLTAGE"3.3V"
HDL_POWER"P3V3_STBY";
"G\NAC"3;
%"GND"
"1","(-6425,475)","0","mstr_symbols","I119";
;
HDL_POWER"GND"
CDS_LIB"mstr_symbols"
VOLTAGE"0.0V"
SIZE"1B"
BODY_TYPE"PLUMBING";
"A\NAC"4;
%"CAP_A"
"1","(-1650,4500)","0","dev_discrete","I120";
;
CDS_LIB"dev_discrete"
CDS_LOCATION"C2T29"
SEC"1"
CDS_SEC"1"
ROOM"M_2"
SEC_TYPE"0402V"
BOM_COST"SD_FLASH"
MATERIAL"X7R"
VOLTAGE"16V"
PACK_TYPE"0402V"
TOLERANCE"10%"
VALUE"0.1UF"
LOCATION"C2T29"
PART_NUMBER"A36096-030";
"B"
$PN"2"5;
"A"
$PN"1"6;
%"GND"
"1","(-1650,4275)","0","mstr_symbols","I122";
;
BODY_TYPE"PLUMBING"
CDS_LIB"mstr_symbols"
VOLTAGE"0.0V"
HDL_POWER"GND"
SIZE"1B";
"A\NAC"5;
%"CAP_A"
"1","(-1400,4500)","0","dev_discrete","I123";
;
CDS_LIB"dev_discrete"
CDS_LOCATION"C2T26"
ROOM"M_2"
BOM_COST"SD_FLASH"
CDS_SEC"1"
SEC"1"
SEC_TYPE"0402V"
VALUE"0.1UF"
LOCATION"C2T26"
MATERIAL"X7R"
VOLTAGE"16V"
PACK_TYPE"0402V"
TOLERANCE"10%"
PART_NUMBER"A36096-030";
"B"
$PN"2"5;
"A"
$PN"1"6;
%"CAP_A"
"1","(-1150,4500)","0","dev_discrete","I124";
;
CDS_LIB"dev_discrete"
CDS_LOCATION"C2T21"
ROOM"M_2"
BOM_COST"SD_FLASH"
CDS_SEC"1"
SEC"1"
SEC_TYPE"0402V"
PART_NUMBER"A36096-030"
MATERIAL"X7R"
VALUE"0.1UF"
TOLERANCE"10%"
PACK_TYPE"0402V"
VOLTAGE"16V"
LOCATION"C2T21";
"B"
$PN"2"5;
"A"
$PN"1"6;
%"P3V3"
"1","(-1650,4725)","0","mstr_symbols","I125";
;
HDL_POWER"P3V3"
BODY_TYPE"PLUMBING"
VOLTAGE"3.3V"
CDS_LIB"mstr_symbols"
SIZE"1B";
"G\NAC"6;
%"CAP_A"
"1","(-1150,3650)","0","dev_discrete","I126";
;
CDS_LIB"dev_discrete"
CDS_LOCATION"C2T16"
CDS_SEC"1"
SEC_TYPE"0402V"
SEC"1"
ROOM"M_2"
BOM_COST"SD_FLASH"
MATERIAL"X7R"
PACK_TYPE"0402V"
TOLERANCE"10%"
VALUE"0.1UF"
VOLTAGE"16V"
LOCATION"C2T16"
PART_NUMBER"A36096-030";
"B"
$PN"2"8;
"A"
$PN"1"7;
%"CAP_A"
"1","(-1400,3650)","0","dev_discrete","I127";
;
CDS_LIB"dev_discrete"
CDS_LOCATION"C2T15"
CDS_SEC"1"
ROOM"M_2"
BOM_COST"SD_FLASH"
SEC"1"
SEC_TYPE"0402V"
MATERIAL"X7R"
VOLTAGE"16V"
PACK_TYPE"0402V"
TOLERANCE"10%"
VALUE"0.1UF"
PART_NUMBER"A36096-030"
LOCATION"C2T15";
"B"
$PN"2"8;
"A"
$PN"1"7;
%"P3V3"
"1","(-1650,3875)","0","mstr_symbols","I128";
;
HDL_POWER"P3V3"
BODY_TYPE"PLUMBING"
VOLTAGE"3.3V"
SIZE"1B"
CDS_LIB"mstr_symbols";
"G\NAC"7;
%"CAP_A"
"1","(-1650,3650)","0","dev_discrete","I129";
;
CDS_LIB"dev_discrete"
CDS_LOCATION"C2T24"
CDS_SEC"1"
BOM_COST"SD_FLASH"
ROOM"M_2"
SEC"1"
SEC_TYPE"0402V"
MATERIAL"X7R"
PACK_TYPE"0402V"
VOLTAGE"16V"
TOLERANCE"10%"
VALUE"0.1UF"
LOCATION"C2T24"
PART_NUMBER"A36096-030";
"B"
$PN"2"8;
"A"
$PN"1"7;
%"GND"
"1","(-1650,3425)","0","mstr_symbols","I130";
;
VOLTAGE"0.0V"
BODY_TYPE"PLUMBING"
CDS_LIB"mstr_symbols"
SIZE"1B"
HDL_POWER"GND";
"A\NAC"8;
%"CAP_A"
"1","(-1150,2800)","0","dev_discrete","I131";
;
CDS_LIB"dev_discrete"
ROOM"M_2"
SEC_TYPE"0402V"
SEC"1"
CDS_SEC"1"
CDS_LOCATION"C2T2"
BOM_COST"SD_FLASH"
MATERIAL"X7R"
VOLTAGE"16V"
PACK_TYPE"0402V"
TOLERANCE"10%"
VALUE"0.1UF"
LOCATION"C2T2"
PART_NUMBER"A36096-030";
"B"
$PN"2"10;
"A"
$PN"1"9;
%"CAP_A"
"1","(-1400,2800)","0","dev_discrete","I132";
;
CDS_LIB"dev_discrete"
CDS_LOCATION"C2T4"
ROOM"M_2"
CDS_SEC"1"
SEC"1"
SEC_TYPE"0402V"
BOM_COST"SD_FLASH"
MATERIAL"X7R"
VOLTAGE"16V"
PACK_TYPE"0402V"
TOLERANCE"10%"
VALUE"0.1UF"
PART_NUMBER"A36096-030"
LOCATION"C2T4";
"B"
$PN"2"10;
"A"
$PN"1"9;
%"P3V3"
"1","(-1650,3025)","0","mstr_symbols","I133";
;
HDL_POWER"P3V3"
VOLTAGE"3.3V"
CDS_LIB"mstr_symbols"
BODY_TYPE"PLUMBING"
SIZE"1B";
"G\NAC"9;
%"GND"
"1","(-1650,2575)","0","mstr_symbols","I134";
;
BODY_TYPE"PLUMBING"
VOLTAGE"0.0V"
SIZE"1B"
CDS_LIB"mstr_symbols"
HDL_POWER"GND";
"A\NAC"10;
%"CAP_A"
"1","(-1650,2800)","0","dev_discrete","I135";
;
CDS_LIB"dev_discrete"
CDS_LOCATION"C2T5"
ROOM"M_2"
CDS_SEC"1"
SEC"1"
SEC_TYPE"0402V"
BOM_COST"SD_FLASH"
MATERIAL"X7R"
VOLTAGE"16V"
PACK_TYPE"0402V"
TOLERANCE"10%"
VALUE"0.1UF"
LOCATION"C2T5"
PART_NUMBER"A36096-030";
"B"
$PN"2"10;
"A"
$PN"1"9;
%"RES"
"2","(-3300,3300)","0","mstr_discrete","I136";
;
CDS_SEC"1"
CDS_LOCATION"R8F36"
BOM_COST"ST_FLASH"
SEC"1"
SEC_TYPE"0402"
ROOM"M_2"
CDS_LIB"mstr_discrete"
PART_NUMBER"G21796-016"
VALUE"10.0K"
LOCATION"R8F36"
TOLERANCE"1%"
WATTAGE"1/16W"
MATERIAL"CHIP"
PACK_TYPE"0402";
"A"
$PN"1"11;
"B"
$PN"2"27;
%"P3V3"
"1","(-3300,3500)","0","mstr_symbols","I137";
;
SIZE"1B"
CDS_LIB"mstr_symbols"
VOLTAGE"3.3V"
BODY_TYPE"PLUMBING"
HDL_POWER"P3V3";
"G\NAC"11;
%"SCONN75K_H17033002"
"2","(-5850,3275)","0","mstr_sconn","I53";
;
CDS_SEC"1"
ROOM"M_2"
SEC_TYPE"SMT1"
BOM_COST"ST_FLASH"
SEC"1"
CDS_LOCATION"J8F1"
PACK_TYPE"SMT1"
CDS_LIB"mstr_sconn"
CDS_LMAN_SYM_OUTLINE"-700,1250,700,-1250"
MATERIAL"SCONN"
LOCATION"J8F1"
PART_NUMBER"H17033-002";
"SUSCLK"
$PN"68"46;
"DEVSLP"
$PN"38"45;
"PEWAKE_N_NC \B"
$PN"54"47;
"PERST_N_NC \B"
$PN"50"48;
"CLKREQ_N_NC \B"
$PN"52"27;
"REFCLKN"
$PN"53"50;
"GND<13>"
$PN"75"12;
"GND<12>"
$PN"73"12;
"GND<11>"
$PN"71"12;
"GND<10>"
$PN"57"12;
"GND<9>"
$PN"51"12;
"GND<8>"
$PN"45"12;
"GND<7>"
$PN"39"12;
"GND<6>"
$PN"33"12;
"GND<3>"
$PN"15"12;
"GND<4>"
$PN"21"12;
"GND<5>"
$PN"27"12;
"GND<2>"
$PN"9"12;
"GND<1>"
$PN"3"12;
"GND<0>"
$PN"1"12;
"DAS_DSS_N"
$PN"10"73;
"NC<18>"
$PN"67"62;
"NC<16>"
$PN"56"70;
"NC<17>"
$PN"58"71;
"NC<14>"
$PN"46"68;
"NC<15>"
$PN"48"69;
"NC<13>"
$PN"44"67;
"NC<12>"
$PN"42"66;
"NC<11>"
$PN"40"65;
"NC<10>"
$PN"36"64;
"NC<9>"
$PN"34"63;
"NC<8>"
$PN"32"56;
"NC<6>"
$PN"28"55;
"NC<7>"
$PN"30"54;
"NC<4>"
$PN"24"61;
"NC<5>"
$PN"26"57;
"NC<3>"
$PN"22"60;
"NC<2>"
$PN"20"59;
"NC<1>"
$PN"8"58;
"3_3V<8>"
$PN"74"13;
"3_3V<7>"
$PN"72"13;
"3_3V<0>"
$PN"2"13;
"3_3V<1>"
$PN"4"13;
"3_3V<2>"
$PN"12"13;
"3_3V<3>"
$PN"14"13;
"3_3V<4>"
$PN"16"13;
"3_3V<5>"
$PN"18"13;
"3_3V<6>"
$PN"70"13;
"NC<0>"
$PN"6"53;
"PEDET"
$PN"69"72;
"MP1"
$PN"MP1"12;
"MP2"
$PN"MP2"12;
"PERN3"
$PN"5"43;
"PERP3"
$PN"7"44;
"PETN3"
$PN"11"18;
"PETP3"
$PN"13"36;
"PERN2"
$PN"17"41;
"PERP2"
$PN"19"42;
"PETN2"
$PN"23"35;
"PETP2"
$PN"25"17;
"PERN1"
$PN"29"39;
"PERP1"
$PN"31"40;
"PETN1"
$PN"35"37;
"PETP1"
$PN"37"38;
"PERN0_SATA_BP"
$PN"41"74;
"PERP0_SATA_BN"
$PN"43"75;
"PETN0_SATA_AN"
$PN"47"77;
"PETP0_SATA_AP"
$PN"49"76;
"REFCLKP"
$PN"55"49;
%"GND"
"1","(-5000,1875)","0","mstr_symbols","I54";
;
HDL_POWER"GND"
VOLTAGE"0.0V"
CDS_LIB"mstr_symbols"
SIZE"1B"
BODY_TYPE"PLUMBING";
"A\NAC"12;
%"P3V3"
"1","(-6725,4775)","0","mstr_symbols","I55";
;
HDL_POWER"P3V3"
BODY_TYPE"PLUMBING"
CDS_LIB"mstr_symbols"
SIZE"1B"
VOLTAGE"3.3V";
"G\NAC"13;
%"CAP"
"2","(-3950,3625)","0","mstr_discrete","I62";
;
CDS_SEC"1"
ROOM"M_2"
BOM_COST"ST_FLASH"
SEC"1"
SEC_TYPE"0402"
CDS_LIB"mstr_discrete"
CDS_LOCATION"C2T11"
PART_NUMBER"A36096-155"
PACK_TYPE"0402"
VOLTAGE"16V"
MATERIAL"X7R"
TOLERANCE"10%"
LOCATION"C2T11"
VALUE"0.22UF";
"A"
$PN"1"37;
"B"
$PN"2"25;
%"CAP"
"2","(-3950,3675)","0","mstr_discrete","I63";
;
CDS_SEC"1"
ROOM"M_2"
BOM_COST"ST_FLASH"
SEC"1"
SEC_TYPE"0402"
CDS_LIB"mstr_discrete"
CDS_LOCATION"C2T10"
PART_NUMBER"A36096-155"
PACK_TYPE"0402"
VOLTAGE"16V"
MATERIAL"X7R"
TOLERANCE"10%"
LOCATION"C2T10"
VALUE"0.22UF";
"A"
$PN"1"38;
"B"
$PN"2"24;
%"CAP"
"2","(-3950,3925)","0","mstr_discrete","I64";
;
CDS_SEC"1"
SEC"1"
SEC_TYPE"0402"
ROOM"M_2"
BOM_COST"ST_FLASH"
CDS_LIB"mstr_discrete"
CDS_LOCATION"C2T13"
PART_NUMBER"A36096-155"
PACK_TYPE"0402"
VOLTAGE"16V"
MATERIAL"X7R"
TOLERANCE"10%"
LOCATION"C2T13"
VALUE"0.22UF";
"A"
$PN"1"17;
"B"
$PN"2"26;
%"CAP"
"2","(-3950,3875)","0","mstr_discrete","I65";
;
CDS_SEC"1"
SEC"1"
SEC_TYPE"0402"
ROOM"M_2"
BOM_COST"ST_FLASH"
CDS_LIB"mstr_discrete"
CDS_LOCATION"C2T14"
VALUE"0.22UF"
LOCATION"C2T14"
PART_NUMBER"A36096-155"
PACK_TYPE"0402"
VOLTAGE"16V"
MATERIAL"X7R"
TOLERANCE"10%";
"A"
$PN"1"35;
"B"
$PN"2"16;
%"CAP"
"2","(-3950,4175)","0","mstr_discrete","I66";
;
CDS_SEC"1"
BOM_COST"ST_FLASH"
ROOM"M_2"
SEC"1"
SEC_TYPE"0402"
CDS_LIB"mstr_discrete"
CDS_LOCATION"C2T20"
PART_NUMBER"A36096-155"
PACK_TYPE"0402"
VOLTAGE"16V"
MATERIAL"X7R"
TOLERANCE"10%"
LOCATION"C2T20"
VALUE"0.22UF";
"A"
$PN"1"36;
"B"
$PN"2"20;
%"CAP"
"2","(-3950,4125)","0","mstr_discrete","I67";
;
CDS_SEC"1"
BOM_COST"ST_FLASH"
ROOM"M_2"
SEC_TYPE"0402"
SEC"1"
CDS_LIB"mstr_discrete"
CDS_LOCATION"C2T23"
PART_NUMBER"A36096-155"
PACK_TYPE"0402"
VOLTAGE"16V"
MATERIAL"X7R"
TOLERANCE"10%"
LOCATION"C2T23"
VALUE"0.22UF";
"A"
$PN"1"18;
"B"
$PN"2"19;
%"CAP_A"
"2","(-2875,850)","0","dev_discrete","I90";
;
CDS_SEC"1"
$SEC"1"
NO_XNET_CONNECTION"1"
ROOM"M_2"
BOM_COST"ST_FLASH"
CDS_LIB"dev_discrete"
CDS_LOCATION"C8F15"
PART_NUMBER"A36096-045"
VOLTAGE"25V"
MATERIAL"EMPTY"
PACK_TYPE"0402V"
VALUE"0.01UF"
TOLERANCE"10%"
LOCATION"C8F15";
"A"
$PN"1"29;
"B"
$PN"2"21;
%"CAP_A"
"2","(-2900,2200)","0","dev_discrete","I95";
;
CDS_SEC"1"
$SEC"1"
BOM_COST"ST_FLASH"
ROOM"M_2"
NO_XNET_CONNECTION"1"
CDS_LIB"dev_discrete"
CDS_LOCATION"C8F6"
MATERIAL"EMPTY"
PART_NUMBER"A36096-045"
PACK_TYPE"0402V"
VOLTAGE"25V"
LOCATION"C8F6"
VALUE"0.01UF"
TOLERANCE"10%";
"A"
$PN"1"14;
"B"
$PN"2"15;
%"CAP"
"2","(-2900,1925)","0","mstr_discrete","I96";
;
CDS_SEC"1"
SEC"1"
SEC_TYPE"0402"
BOM_COST"ST_FLASH"
ROOM"M_2"
CDS_LIB"mstr_discrete"
CDS_LOCATION"C8F7"
PACK_TYPE"0402"
PART_NUMBER"A36096-155"
MATERIAL"X7R"
VOLTAGE"16V"
TOLERANCE"10%"
VALUE"0.22UF"
LOCATION"C8F7";
"A"
$PN"1"34;
"B"
$PN"2"15;
%"CAP_A"
"2","(-2900,1700)","0","dev_discrete","I97";
;
CDS_SEC"1"
$SEC"1"
ROOM"M_2"
BOM_COST"ST_FLASH"
NO_XNET_CONNECTION"1"
CDS_LIB"dev_discrete"
CDS_LOCATION"C8F11"
PART_NUMBER"A36096-045"
PACK_TYPE"0402V"
VOLTAGE"25V"
VALUE"0.01UF"
TOLERANCE"10%"
LOCATION"C8F11"
MATERIAL"EMPTY";
"A"
$PN"1"33;
"B"
$PN"2"23;
%"CAP"
"2","(-2900,1475)","0","mstr_discrete","I98";
;
CDS_SEC"1"
BOM_COST"ST_FLASH"
ROOM"M_2"
SEC_TYPE"0402"
SEC"1"
CDS_LIB"mstr_discrete"
CDS_LOCATION"C8F12"
PART_NUMBER"A36096-155"
PACK_TYPE"0402"
MATERIAL"X7R"
VOLTAGE"16V"
TOLERANCE"10%"
VALUE"0.22UF"
LOCATION"C8F12";
"A"
$PN"1"32;
"B"
$PN"2"23;
%"CAP_A"
"2","(-2900,1275)","0","dev_discrete","I99";
;
$SEC"1"
BOM_COST"ST_FLASH"
ROOM"M_2"
NO_XNET_CONNECTION"1"
CDS_SEC"1"
CDS_LIB"dev_discrete"
CDS_LOCATION"C8F13"
PACK_TYPE"0402V"
VOLTAGE"25V"
PART_NUMBER"A36096-045"
MATERIAL"EMPTY"
TOLERANCE"10%"
VALUE"0.01UF"
LOCATION"C8F13";
"A"
$PN"1"31;
"B"
$PN"2"22;
END.
